# S9S_MB_2U (Grand Teton) — schematic netlist excerpt (pin names and nets, part order shuffled) for the footprints in the layout excerpt that follows; sources: Cadence DE-HDL packaged netlist, KiCad conversion of 03242023_DA0F0TMBIJ0_F0T_Motherboard_J_brd_V01_OCP.brd

C968  Q_CAP  10UF 6.3V 20% X6S  pkg C0402  page 74 : A = PVCCIN_CPU0 ; B = GND
C853  Q_CAP_DIFFBUS  DIFF BUS_0.22UF 6.3V 20% X6S  pkg C0201  page 174 : \1\ = P5E_CPU0_PE1_TX_C_DP<8> ; \2\ = P5E_CPU0_PE1_TX_DP<8>
R4216  Q_RES  0 5% CHIP  pkg 0402LF  page 266 : A = FM_PVCCFA_EHV_FIVRA_CPU0_EN ; B = PVCCFA_EHV_FIVRA_CPU0_EN_R

(kicad_pcb
	(version 20260206)
	(generator "pcbnew")
	(generator_version "10.0")
	(general
		(thickness 1.6)
		(legacy_teardrops no)
	)
	(paper "A4")
	(title_block
		(title "03242023_DA0F0TMBIJ0_F0T_Motherboard_J_brd_V01_OCP.brd")
		(comment 1 "Grand Teton / footprints 2581-2583 of 6105")
	)
	(layers
		(0 "F.Cu" signal "TOP")
		(4 "In1.Cu" signal "GND")
		(6 "In2.Cu" signal "IN1")
		(8 "In3.Cu" signal "GND1")
		(10 "In4.Cu" signal "IN2")
		(12 "In5.Cu" signal "GND2")
		(14 "In6.Cu" signal "IN3")
		(16 "In7.Cu" signal "GND3")
		(18 "In8.Cu" signal "VCC")
		(20 "In9.Cu" signal "VCC1")
		(22 "In10.Cu" signal "GND4")
		(24 "In11.Cu" signal "IN4")
		(26 "In12.Cu" signal "GND5")
		(28 "In13.Cu" signal "IN5")
		(30 "In14.Cu" signal "GND6")
		(32 "In15.Cu" signal "IN6")
		(34 "In16.Cu" signal "GND7")
		(2 "B.Cu" signal "BOTTOM")
		(9 "F.Adhes" user "F.Adhesive")
		(11 "B.Adhes" user "B.Adhesive")
		(13 "F.Paste" user "Package Geometry/Pastemask Top")
		(15 "B.Paste" user "Package Geometry/Pastemask Bottom")
		(5 "F.SilkS" user "Ref Des/Silkscreen Top")
		(7 "B.SilkS" user "Ref Des/Silkscreen Bottom")
		(1 "F.Mask" user "Board Geometry/Soldermask Top")
		(3 "B.Mask" user "Board Geometry/Soldermask Bottom")
		(17 "Dwgs.User" user "User.Drawings")
		(19 "Cmts.User" user "User.Comments")
		(21 "Eco1.User" user "User.Eco1")
		(23 "Eco2.User" user "User.Eco2")
		(25 "Edge.Cuts" user "Board Geometry/Outline")
		(27 "Margin" user)
		(31 "F.CrtYd" user "Package Geometry/Place Bound Top")
		(29 "B.CrtYd" user "Package Geometry/Place Bound Bottom")
		(35 "F.Fab" user "Ref Des/Assembly Top")
		(33 "B.Fab" user "Ref Des/Assembly Bottom")
	)
	(footprint ""
		(layer "F.Cu")
		(at 364.50143 -258.726686 90)
		(property "Reference" "C968"
			(at 0 0 90)
			(layer "F.SilkS")
			(hide yes)
			(effects
				(font
					(size 1.27 1.27)
				)
			)
		)
		(property "Value" ""
			(at 0 0 90)
			(layer "F.Fab")
			(effects
				(font
					(size 1.27 1.27)
				)
			)
		)
		(duplicate_pad_numbers_are_jumpers no)
		(fp_line
			(start 0.7874 -0.4064)
			(end 0.7874 0.4064)
			(stroke
				(width 0.1524)
				(type default)
			)
			(layer "F.SilkS")
		)
		(fp_line
			(start -0.7874 -0.4064)
			(end 0.7874 -0.4064)
			(stroke
				(width 0.1524)
				(type default)
			)
			(layer "F.SilkS")
		)
		(fp_line
			(start 0.7874 0.4064)
			(end -0.7874 0.4064)
			(stroke
				(width 0.1524)
				(type default)
			)
			(layer "F.SilkS")
		)
		(fp_line
			(start -0.7874 0.4064)
			(end -0.7874 -0.4064)
			(stroke
				(width 0.1524)
				(type default)
			)
			(layer "F.SilkS")
		)
		(fp_line
			(start -0.12065 -0.305054)
			(end -0.12065 -0.2794)
			(stroke
				(width 0.1)
				(type default)
			)
			(layer "F.Fab")
		)
		(fp_line
			(start -0.67945 -0.305054)
			(end -0.12065 -0.305054)
			(stroke
				(width 0.1)
				(type default)
			)
			(layer "F.Fab")
		)
		(fp_line
			(start 0.67945 -0.3048)
			(end 0.67945 0.3048)
			(stroke
				(width 0.1)
				(type default)
			)
			(layer "F.Fab")
		)
		(fp_line
			(start 0.12065 -0.3048)
			(end 0.67945 -0.3048)
			(stroke
				(width 0.1)
				(type default)
			)
			(layer "F.Fab")
		)
		(fp_line
			(start 0.12065 -0.2794)
			(end 0.12065 -0.3048)
			(stroke
				(width 0.1)
				(type default)
			)
			(layer "F.Fab")
		)
		(fp_line
			(start -0.12065 -0.2794)
			(end 0.12065 -0.2794)
			(stroke
				(width 0.1)
				(type default)
			)
			(layer "F.Fab")
		)
		(fp_line
			(start 0.120396 0.2794)
			(end -0.12065 0.2794)
			(stroke
				(width 0.1)
				(type default)
			)
			(layer "F.Fab")
		)
		(fp_line
			(start -0.12065 0.2794)
			(end -0.12065 0.3048)
			(stroke
				(width 0.1)
				(type default)
			)
			(layer "F.Fab")
		)
		(fp_line
			(start 0.67945 0.3048)
			(end 0.120396 0.3048)
			(stroke
				(width 0.1)
				(type default)
			)
			(layer "F.Fab")
		)
		(fp_line
			(start 0.120396 0.3048)
			(end 0.120396 0.2794)
			(stroke
				(width 0.1)
				(type default)
			)
			(layer "F.Fab")
		)
		(fp_line
			(start -0.12065 0.3048)
			(end -0.67945 0.3048)
			(stroke
				(width 0.1)
				(type default)
			)
			(layer "F.Fab")
		)
		(fp_line
			(start -0.67945 0.3048)
			(end -0.67945 -0.305054)
			(stroke
				(width 0.1)
				(type default)
			)
			(layer "F.Fab")
		)
		(pad "1" smd circle
			(at -0.40005 0 90)
			(size 0 0)
			(layers "F.Cu" "F.Mask" "F.Paste")
			(net "PVCCIN_CPU0")
		)
		(pad "2" smd circle
			(at 0.40005 0 90)
			(size 0 0)
			(layers "F.Cu" "F.Mask" "F.Paste")
			(net "GND")
		)
	)
	(footprint ""
		(layer "F.Cu")
		(at 351.116138 -354.483162 90)
		(property "Reference" "R4216"
			(at 0 0 90)
			(layer "F.SilkS")
			(hide yes)
			(effects
				(font
					(size 1.27 1.27)
				)
			)
		)
		(property "Value" ""
			(at 0 0 90)
			(layer "F.Fab")
			(effects
				(font
					(size 1.27 1.27)
				)
			)
		)
		(duplicate_pad_numbers_are_jumpers no)
		(fp_line
			(start 0.7874 -0.4064)
			(end 0.7874 0.4064)
			(stroke
				(width 0.1524)
				(type default)
			)
			(layer "F.SilkS")
		)
		(fp_line
			(start -0.7874 -0.4064)
			(end 0.7874 -0.4064)
			(stroke
				(width 0.1524)
				(type default)
			)
			(layer "F.SilkS")
		)
		(fp_line
			(start 0.7874 0.4064)
			(end -0.7874 0.4064)
			(stroke
				(width 0.1524)
				(type default)
			)
			(layer "F.SilkS")
		)
		(fp_line
			(start -0.7874 0.4064)
			(end -0.7874 -0.4064)
			(stroke
				(width 0.1524)
				(type default)
			)
			(layer "F.SilkS")
		)
		(fp_line
			(start -0.12065 -0.305054)
			(end -0.12065 -0.2794)
			(stroke
				(width 0.1)
				(type default)
			)
			(layer "F.Fab")
		)
		(fp_line
			(start -0.67945 -0.305054)
			(end -0.12065 -0.305054)
			(stroke
				(width 0.1)
				(type default)
			)
			(layer "F.Fab")
		)
		(fp_line
			(start 0.67945 -0.3048)
			(end 0.67945 0.3048)
			(stroke
				(width 0.1)
				(type default)
			)
			(layer "F.Fab")
		)
		(fp_line
			(start 0.12065 -0.3048)
			(end 0.67945 -0.3048)
			(stroke
				(width 0.1)
				(type default)
			)
			(layer "F.Fab")
		)
		(fp_line
			(start 0.12065 -0.2794)
			(end 0.12065 -0.3048)
			(stroke
				(width 0.1)
				(type default)
			)
			(layer "F.Fab")
		)
		(fp_line
			(start -0.12065 -0.2794)
			(end 0.12065 -0.2794)
			(stroke
				(width 0.1)
				(type default)
			)
			(layer "F.Fab")
		)
		(fp_line
			(start 0.120396 0.2794)
			(end -0.12065 0.2794)
			(stroke
				(width 0.1)
				(type default)
			)
			(layer "F.Fab")
		)
		(fp_line
			(start -0.12065 0.2794)
			(end -0.12065 0.3048)
			(stroke
				(width 0.1)
				(type default)
			)
			(layer "F.Fab")
		)
		(fp_line
			(start 0.67945 0.3048)
			(end 0.120396 0.3048)
			(stroke
				(width 0.1)
				(type default)
			)
			(layer "F.Fab")
		)
		(fp_line
			(start 0.120396 0.3048)
			(end 0.120396 0.2794)
			(stroke
				(width 0.1)
				(type default)
			)
			(layer "F.Fab")
		)
		(fp_line
			(start -0.12065 0.3048)
			(end -0.67945 0.3048)
			(stroke
				(width 0.1)
				(type default)
			)
			(layer "F.Fab")
		)
		(fp_line
			(start -0.67945 0.3048)
			(end -0.67945 -0.305054)
			(stroke
				(width 0.1)
				(type default)
			)
			(layer "F.Fab")
		)
		(pad "1" smd circle
			(at -0.40005 0 90)
			(size 0 0)
			(layers "F.Cu" "F.Mask" "F.Paste")
			(net "FM_PVCCFA_EHV_FIVRA_CPU0_EN")
		)
		(pad "2" smd circle
			(at 0.40005 0 90)
			(size 0 0)
			(layers "F.Cu" "F.Mask" "F.Paste")
			(net "PVCCFA_EHV_FIVRA_CPU0_EN_R")
		)
	)
	(footprint ""
		(layer "F.Cu")
		(at 410.488384 -17.612614 90)
		(property "Reference" "C853"
			(at 0 0 90)
			(layer "F.SilkS")
			(hide yes)
			(effects
				(font
					(size 1.27 1.27)
				)
			)
		)
		(property "Value" ""
			(at 0 0 90)
			(layer "F.Fab")
			(effects
				(font
					(size 1.27 1.27)
				)
			)
		)
		(duplicate_pad_numbers_are_jumpers no)
		(fp_line
			(start 0.299974 -0.150114)
			(end 0.299974 0.150114)
			(stroke
				(width 0.1)
				(type default)
			)
			(layer "F.Fab")
		)
		(fp_line
			(start -0.299974 -0.150114)
			(end 0.299974 -0.150114)
			(stroke
				(width 0.1)
				(type default)
			)
			(layer "F.Fab")
		)
		(fp_line
			(start 0.299974 0.150114)
			(end -0.299974 0.150114)
			(stroke
				(width 0.1)
				(type default)
			)
			(layer "F.Fab")
		)
		(fp_line
			(start -0.299974 0.150114)
			(end -0.299974 -0.150114)
			(stroke
				(width 0.1)
				(type default)
			)
			(layer "F.Fab")
		)
		(pad "1" smd rect
			(at -0.2667 0 90)
			(size 0.3048 0.381)
			(layers "F.Cu" "F.Mask" "F.Paste")
			(net "P5E_CPU0_PE1_TX_C_DP<8>")
		)
		(pad "2" smd rect
			(at 0.2667 0 90)
			(size 0.3048 0.381)
			(layers "F.Cu" "F.Mask" "F.Paste")
			(net "P5E_CPU0_PE1_TX_DP<8>")
		)
	)
)
